(kicad_pcb
	(version 20260206)
	(generator "pcbnew")
	(generator_version "10.0")
	(general
		(thickness 1.6)
		(legacy_teardrops no)
	)
	(paper "A4")
	(title_block
		(title "netronome-mezz — pcbd0082-001_rev01_jul9_a.brd")
		(comment 1 "Open CloudServer (Microsoft) / footprints 81-84 of 714")
	)
	(layers
		(0 "F.Cu" signal "TOP")
		(4 "In1.Cu" signal "02_GND")
		(6 "In2.Cu" signal "03_SIG")
		(8 "In3.Cu" signal "04_SIG")
		(10 "In4.Cu" signal "05_GND")
		(12 "In5.Cu" signal "06_PWR1")
		(14 "In6.Cu" signal "07_SIG")
		(16 "In7.Cu" signal "08_SIG")
		(18 "In8.Cu" signal "09_GND")
		(2 "B.Cu" signal "BOTTOM")
		(9 "F.Adhes" user "F.Adhesive")
		(11 "B.Adhes" user "B.Adhesive")
		(13 "F.Paste" user "Package Geometry/Pastemask Top")
		(15 "B.Paste" user "Package Geometry/Pastemask Bottom")
		(5 "F.SilkS" user "Ref Des/Silkscreen Top")
		(7 "B.SilkS" user "Ref Des/Silkscreen Bottom")
		(1 "F.Mask" user "Board Geometry/Soldermask Top")
		(3 "B.Mask" user "Board Geometry/Soldermask Bottom")
		(17 "Dwgs.User" user "User.Drawings")
		(19 "Cmts.User" user "User.Comments")
		(21 "Eco1.User" user "User.Eco1")
		(23 "Eco2.User" user "User.Eco2")
		(25 "Edge.Cuts" user "Board Geometry/Outline")
		(27 "Margin" user)
		(31 "F.CrtYd" user "Package Geometry/Place Bound Top")
		(29 "B.CrtYd" user "Package Geometry/Place Bound Bottom")
		(35 "F.Fab" user "Ref Des/Assembly Top")
		(33 "B.Fab" user "Ref Des/Assembly Bottom")
		(45 "User.4" user "COMPVAL_TYPE_BOTTOM")
	)
	(footprint ""
		(layer "F.Cu")
		(at 5.334 10.16 180)
		(property "Reference" "C243"
			(at 6.32333 2.54 90)
			(unlocked yes)
			(layer "F.SilkS")
			(effects
				(font
					(size 0.7874 0.5842)
					(thickness 0.127)
				)
				(justify left)
			)
		)
		(property "Value" "220UF"
			(at -0.4826 1.37668 180)
			(unlocked yes)
			(layer "F.Fab")
			(hide yes)
			(effects
				(font
					(size 1.27 0.9652)
					(thickness 0.000001)
				)
				(justify left)
			)
		)
		(property "Device Type" "CAPE0005"
			(at -0.4826 1.37668 180)
			(unlocked yes)
			(layer "F.Fab")
			(hide yes)
			(effects
				(font
					(size 1.27 0.9652)
					(thickness 0.000001)
				)
				(justify left)
			)
		)
		(duplicate_pad_numbers_are_jumpers no)
		(fp_line
			(start 5.588 5.588)
			(end 5.588 -3.302)
			(stroke
				(width 0.2032)
				(type default)
			)
			(layer "F.SilkS")
		)
		(fp_line
			(start 5.588 5.588)
			(end 5.588 -3.302)
			(stroke
				(width 0.2032)
				(type default)
			)
			(layer "F.SilkS")
		)
		(fp_line
			(start 5.588 -3.302)
			(end 4.673041 -4.216959)
			(stroke
				(width 0.2032)
				(type default)
			)
			(layer "F.SilkS")
		)
		(fp_line
			(start 5.588 -3.302)
			(end 3.302 -5.588)
			(stroke
				(width 0.2032)
				(type default)
			)
			(layer "F.SilkS")
		)
		(fp_line
			(start 4.089959 -4.800041)
			(end 3.302 -5.588)
			(stroke
				(width 0.2032)
				(type default)
			)
			(layer "F.SilkS")
		)
		(fp_line
			(start 3.302 -5.588)
			(end 1.3081 -5.588)
			(stroke
				(width 0.2032)
				(type default)
			)
			(layer "F.SilkS")
		)
		(fp_line
			(start 3.302 -5.588)
			(end 1.27 -5.588)
			(stroke
				(width 0.2032)
				(type default)
			)
			(layer "F.SilkS")
		)
		(fp_line
			(start 2.0066 -7.1374)
			(end 2.0066 -5.8674)
			(stroke
				(width 0.2032)
				(type default)
			)
			(layer "F.SilkS")
		)
		(fp_line
			(start 2.0066 -7.1374)
			(end 2.0066 -5.8674)
			(stroke
				(width 0.2032)
				(type default)
			)
			(layer "F.SilkS")
		)
		(fp_line
			(start 1.733956 5.588)
			(end 5.588 5.588)
			(stroke
				(width 0.2032)
				(type default)
			)
			(layer "F.SilkS")
		)
		(fp_line
			(start 1.3716 -6.5024)
			(end 2.6416 -6.5024)
			(stroke
				(width 0.2032)
				(type default)
			)
			(layer "F.SilkS")
		)
		(fp_line
			(start 1.3716 -6.5024)
			(end 2.6416 -6.5024)
			(stroke
				(width 0.2032)
				(type default)
			)
			(layer "F.SilkS")
		)
		(fp_line
			(start 1.27 5.588)
			(end 5.588 5.588)
			(stroke
				(width 0.2032)
				(type default)
			)
			(layer "F.SilkS")
		)
		(fp_line
			(start -1.27 -5.588)
			(end -3.302 -5.588)
			(stroke
				(width 0.2032)
				(type default)
			)
			(layer "F.SilkS")
		)
		(fp_line
			(start -3.302 -5.588)
			(end -5.588 -3.302)
			(stroke
				(width 0.2032)
				(type default)
			)
			(layer "F.SilkS")
		)
		(fp_line
			(start -5.588 5.588)
			(end -1.27 5.588)
			(stroke
				(width 0.2032)
				(type default)
			)
			(layer "F.SilkS")
		)
		(fp_line
			(start -5.588 -3.302)
			(end -5.588 5.588)
			(stroke
				(width 0.2032)
				(type default)
			)
			(layer "F.SilkS")
		)
		(fp_line
			(start -5.588 -3.302)
			(end -5.588 5.588)
			(stroke
				(width 0.2032)
				(type default)
			)
			(layer "F.SilkS")
		)
		(fp_poly
			(pts
				(xy -5.7912 -5.842) (xy -1.524 -5.842) (xy -1.524 -7.112) (xy 1.524 -7.112) (xy 1.524 -5.842) (xy 5.261026 -5.842)
				(xy 5.261026 5.842) (xy 1.524 5.842) (xy 1.524 7.112) (xy -1.524 7.112) (xy -1.524 5.842) (xy -5.7912 5.842)
			)
			(stroke
				(width 0)
				(type default)
			)
			(fill no)
			(layer "F.CrtYd")
		)
		(fp_line
			(start 5.2578 5.2578)
			(end 5.2578 -3.2258)
			(stroke
				(width 0.2032)
				(type default)
			)
			(layer "F.Fab")
		)
		(fp_line
			(start 5.2578 -3.2258)
			(end 3.2258 -5.2578)
			(stroke
				(width 0.2032)
				(type default)
			)
			(layer "F.Fab")
		)
		(fp_line
			(start 3.2258 -5.2578)
			(end -3.2258 -5.2578)
			(stroke
				(width 0.2032)
				(type default)
			)
			(layer "F.Fab")
		)
		(fp_line
			(start 0.635 -3.937)
			(end -0.635 -3.937)
			(stroke
				(width 0.2032)
				(type default)
			)
			(layer "F.Fab")
		)
		(fp_line
			(start 0 -4.572)
			(end 0 -3.302)
			(stroke
				(width 0.2032)
				(type default)
			)
			(layer "F.Fab")
		)
		(fp_line
			(start -3.2258 -5.2578)
			(end -5.2578 -3.2258)
			(stroke
				(width 0.2032)
				(type default)
			)
			(layer "F.Fab")
		)
		(fp_line
			(start -5.2578 5.2578)
			(end 5.2578 5.2578)
			(stroke
				(width 0.2032)
				(type default)
			)
			(layer "F.Fab")
		)
		(fp_line
			(start -5.2578 -3.2258)
			(end -5.2578 5.2578)
			(stroke
				(width 0.2032)
				(type default)
			)
			(layer "F.Fab")
		)
		(pad "1" smd rect
			(at 0 -4.3561 180)
			(size 1.905 4.4196)
			(layers "F.Cu" "F.Mask" "F.Paste")
			(net "EXT_12.0V")
		)
		(pad "2" smd rect
			(at 0 4.3561 180)
			(size 1.905 4.4196)
			(layers "F.Cu" "F.Mask" "F.Paste")
			(net "GND")
		)
	)
	(footprint ""
		(layer "F.Cu")
		(at 42.291 43.307)
		(property "Reference" "C60"
			(at 1.29667 -2.159 90)
			(unlocked yes)
			(layer "F.SilkS")
			(effects
				(font
					(size 0.7874 0.5842)
					(thickness 0.127)
				)
				(justify left)
			)
		)
		(property "Value" "100UF"
			(at -0.78232 0.4826 90)
			(unlocked yes)
			(layer "F.Fab")
			(hide yes)
			(effects
				(font
					(size 1.27 0.9652)
					(thickness 0.000001)
				)
				(justify left)
			)
		)
		(property "Device Type" "CAPC0087"
			(at -0.78232 0.4826 90)
			(unlocked yes)
			(layer "F.Fab")
			(hide yes)
			(effects
				(font
					(size 1.27 0.9652)
					(thickness 0.000001)
				)
				(justify left)
			)
		)
		(duplicate_pad_numbers_are_jumpers no)
		(fp_circle
			(center 0 0)
			(end 0.508 0)
			(stroke
				(width 0.2032)
				(type default)
			)
			(fill no)
			(layer "F.SilkS")
		)
		(fp_circle
			(center 0 0)
			(end 0.508 0)
			(stroke
				(width 0.2032)
				(type default)
			)
			(fill no)
			(layer "F.SilkS")
		)
		(fp_poly
			(pts
				(xy -1.27 2.9464) (xy 1.27 2.9464) (xy 1.27 -2.9464) (xy -1.27 -2.9464)
			)
			(stroke
				(width 0)
				(type default)
			)
			(fill no)
			(layer "F.CrtYd")
		)
		(fp_line
			(start -1.016 -2.794)
			(end 1.016 -2.794)
			(stroke
				(width 0.0254)
				(type default)
			)
			(layer "F.Fab")
		)
		(fp_line
			(start -1.016 2.794)
			(end -1.016 -2.794)
			(stroke
				(width 0.0254)
				(type default)
			)
			(layer "F.Fab")
		)
		(fp_line
			(start 1.016 -2.794)
			(end 1.016 2.794)
			(stroke
				(width 0.0254)
				(type default)
			)
			(layer "F.Fab")
		)
		(fp_line
			(start 1.016 2.794)
			(end -1.016 2.794)
			(stroke
				(width 0.0254)
				(type default)
			)
			(layer "F.Fab")
		)
		(pad "1" smd rect
			(at 0 -1.6764)
			(size 1.524 1.524)
			(layers "F.Cu" "F.Mask" "F.Paste")
			(net "VDD_CORE")
		)
		(pad "2" smd rect
			(at 0 1.6764)
			(size 1.524 1.524)
			(layers "F.Cu" "F.Mask" "F.Paste")
			(net "GND")
		)
		(zone
			(layer "F.Cu")
			(hatch none 0.5)
			(connect_pads
				(clearance 0)
			)
			(min_thickness 0.25)
			(keepout
				(tracks not_allowed)
				(vias allowed)
				(pads allowed)
				(copperpour not_allowed)
				(footprints allowed)
			)
			(placement
				(enabled no)
				(sheetname "")
			)
			(fill
				(thermal_gap 0.5)
				(thermal_bridge_width 0.5)
				(island_removal_mode 0)
			)
			(polygon
				(pts
					(xy 41.5036 42.418) (xy 43.0784 42.418) (xy 43.0784 42.5704) (xy 41.5036 42.5704)
				)
			)
		)
		(zone
			(layer "F.Cu")
			(hatch none 0.5)
			(connect_pads
				(clearance 0)
			)
			(min_thickness 0.25)
			(keepout
				(tracks not_allowed)
				(vias allowed)
				(pads allowed)
				(copperpour not_allowed)
				(footprints allowed)
			)
			(placement
				(enabled no)
				(sheetname "")
			)
			(fill
				(thermal_gap 0.5)
				(thermal_bridge_width 0.5)
				(island_removal_mode 0)
			)
			(polygon
				(pts
					(xy 41.5036 44.0436) (xy 43.0784 44.0436) (xy 43.0784 44.196) (xy 41.5036 44.196)
				)
			)
		)
		(zone
			(layer "F.Cu")
			(hatch none 0.5)
			(connect_pads
				(clearance 0)
			)
			(min_thickness 0.25)
			(keepout
				(tracks allowed)
				(vias not_allowed)
				(pads allowed)
				(copperpour not_allowed)
				(footprints allowed)
			)
			(placement
				(enabled no)
				(sheetname "")
			)
			(fill
				(thermal_gap 0.5)
				(thermal_bridge_width 0.5)
				(island_removal_mode 0)
			)
			(polygon
				(pts
					(xy 41.5036 44.9072) (xy 43.0784 44.9072) (xy 43.0784 41.7068) (xy 41.5036 41.7068)
				)
			)
		)
	)
	(footprint ""
		(layer "F.Cu")
		(at 23.6601 6.35 -90)
		(property "Reference" "R382"
			(at 0.15367 -0.8509 0)
			(unlocked yes)
			(layer "F.SilkS")
			(effects
				(font
					(size 0.7874 0.5842)
					(thickness 0.127)
				)
				(justify left)
			)
		)
		(property "Value" "0"
			(at -0.148158 1.3462 0)
			(unlocked yes)
			(layer "F.Fab")
			(hide yes)
			(effects
				(font
					(size 1.27 0.9652)
					(thickness 0.000001)
				)
				(justify left)
			)
		)
		(property "Device Type" "REST1111"
			(at -0.148158 1.3462 0)
			(unlocked yes)
			(layer "F.Fab")
			(hide yes)
			(effects
				(font
					(size 1.27 0.9652)
					(thickness 0.000001)
				)
				(justify left)
			)
		)
		(duplicate_pad_numbers_are_jumpers no)
		(fp_poly
			(pts
				(xy 0.635 1.0668) (xy 0.635 -1.0668) (xy -0.635 -1.0668) (xy -0.635 1.0668)
			)
			(stroke
				(width 0)
				(type default)
			)
			(fill no)
			(layer "F.CrtYd")
		)
		(fp_line
			(start -0.254 0.508)
			(end -0.254 -0.508)
			(stroke
				(width 0.0254)
				(type default)
			)
			(layer "F.Fab")
		)
		(fp_line
			(start 0.254 0.508)
			(end -0.254 0.508)
			(stroke
				(width 0.0254)
				(type default)
			)
			(layer "F.Fab")
		)
		(fp_line
			(start -0.254 -0.508)
			(end 0.254 -0.508)
			(stroke
				(width 0.0254)
				(type default)
			)
			(layer "F.Fab")
		)
		(fp_line
			(start 0.254 -0.508)
			(end 0.254 0.508)
			(stroke
				(width 0.0254)
				(type default)
			)
			(layer "F.Fab")
		)
		(pad "1" smd rect
			(at 0 -0.4191 270)
			(size 0.508 0.5334)
			(layers "F.Cu" "F.Mask" "F.Paste")
			(net "NFP_SMBUS_SDA")
		)
		(pad "2" smd rect
			(at 0 0.4191 270)
			(size 0.508 0.5334)
			(layers "F.Cu" "F.Mask" "F.Paste")
			(net "MUX_NFP_SMBUS_SDA")
		)
		(zone
			(layer "F.Cu")
			(hatch none 0.5)
			(connect_pads
				(clearance 0)
			)
			(min_thickness 0.25)
			(keepout
				(tracks not_allowed)
				(vias allowed)
				(pads allowed)
				(copperpour not_allowed)
				(footprints allowed)
			)
			(placement
				(enabled no)
				(sheetname "")
			)
			(fill
				(thermal_gap 0.5)
				(thermal_bridge_width 0.5)
				(island_removal_mode 0)
			)
			(polygon
				(pts
					(xy 23.6855 6.3754) (xy 23.6347 6.3754) (xy 23.6347 6.3246) (xy 23.6855 6.3246)
				)
			)
		)
	)
	(footprint ""
		(layer "F.Cu")
		(at 77.343 46.863 180)
		(property "Reference" "L9"
			(at 2.25933 -0.127 90)
			(unlocked yes)
			(layer "F.SilkS")
			(effects
				(font
					(size 0.7874 0.5842)
					(thickness 0.127)
				)
				(justify left)
			)
		)
		(property "Value" "1.0UH"
			(at -0.483362 -0.148082 180)
			(unlocked yes)
			(layer "F.Fab")
			(hide yes)
			(effects
				(font
					(size 1.27 0.9652)
					(thickness 0.000001)
				)
				(justify left)
			)
		)
		(property "Device Type" "INDS0061"
			(at -0.483362 -0.148082 180)
			(unlocked yes)
			(layer "F.Fab")
			(hide yes)
			(effects
				(font
					(size 1.27 0.9652)
					(thickness 0.000001)
				)
				(justify left)
			)
		)
		(duplicate_pad_numbers_are_jumpers no)
		(fp_line
			(start 1.27 1.397)
			(end -1.27 1.397)
			(stroke
				(width 0.1524)
				(type default)
			)
			(layer "F.SilkS")
		)
		(fp_line
			(start -1.27 -1.397)
			(end 1.27 -1.397)
			(stroke
				(width 0.1524)
				(type default)
			)
			(layer "F.SilkS")
		)
		(fp_poly
			(pts
				(xy 2.159 -1.651) (xy 2.159 1.651) (xy -2.159 1.651) (xy -2.159 -1.651)
			)
			(stroke
				(width 0)
				(type default)
			)
			(fill no)
			(layer "F.CrtYd")
		)
		(fp_line
			(start 1.3462 1.1049)
			(end 1.3462 -1.1049)
			(stroke
				(width 0.1524)
				(type default)
			)
			(layer "F.Fab")
		)
		(fp_line
			(start 1.3462 -1.1049)
			(end -1.3462 -1.1049)
			(stroke
				(width 0.1524)
				(type default)
			)
			(layer "F.Fab")
		)
		(fp_line
			(start -1.3462 1.1049)
			(end 1.3462 1.1049)
			(stroke
				(width 0.1524)
				(type default)
			)
			(layer "F.Fab")
		)
		(fp_line
			(start -1.3462 -1.1049)
			(end -1.3462 1.1049)
			(stroke
				(width 0.1524)
				(type default)
			)
			(layer "F.Fab")
		)
		(pad "1" smd rect
			(at -1.1303 0 180)
			(size 1.1938 2.3368)
			(layers "F.Cu" "F.Mask" "F.Paste")
			(net "11N2253")
		)
		(pad "2" smd rect
			(at 1.1303 0 180)
			(size 1.1938 2.3368)
			(layers "F.Cu" "F.Mask" "F.Paste")
			(net "DDR_VDDQ")
		)
		(zone
			(layer "F.Cu")
			(hatch none 0.5)
			(connect_pads
				(clearance 0)
			)
			(min_thickness 0.25)
			(keepout
				(tracks allowed)
				(vias not_allowed)
				(pads allowed)
				(copperpour not_allowed)
				(footprints allowed)
			)
			(placement
				(enabled no)
				(sheetname "")
			)
			(fill
				(thermal_gap 0.5)
				(thermal_bridge_width 0.5)
				(island_removal_mode 0)
			)
			(polygon
				(pts
					(xy 78.6892 45.7581) (xy 76.327 45.7581) (xy 76.327 47.9679) (xy 78.6892 47.9679)
				)
			)
		)
	)
)
